FILE_TYPE = MACRO_DRAWING;
SET COLOR_WIRE YELLOW;
SET COLOR_PROP ORANGE;
SET COLOR_DOT WHITE;
SET COLOR_ARC YELLOW;
SET COLOR_BODY GREEN;
SET COLOR_NOTE PURPLE;
SET PROP_DISPLAY VALUE;
SET PAGE_NUMBER P4;
FORCEADD QUANTA_TITLE_BLOCK_C..2
(-100 100);
FORCEPROP 1 LAST Q_TITLE TABLE OF CONTENT 3/3
J 0
(-9416 151);
DISPLAY 2.446809 (-9416 151);
PAINT GREEN (-9416 151);
FORCEPROP 1 LAST CUSTOM_TXT_CDS <CON_TC_SNM1>
J 0
(-7700 5675);
FORCEPROP 1 LAST CUSTOM_TXT_CDS <CON_TC_SNM2>
J 0
(-7700 5575);
FORCEPROP 1 LAST CUSTOM_TXT_CDS <CON_TC_SNM3>
J 0
(-7700 5475);
FORCEPROP 1 LAST CUSTOM_TXT_CDS <CON_TC_SNM4>
J 0
(-7700 5375);
FORCEPROP 1 LAST CUSTOM_TXT_CDS <CON_TC_SNM5>
J 0
(-7700 5275);
FORCEPROP 1 LAST CUSTOM_TXT_CDS <CON_TC_SNM6>
J 0
(-7700 5175);
FORCEPROP 1 LAST CUSTOM_TXT_CDS <CON_TC_SNM7>
J 0
(-7700 5075);
FORCEPROP 1 LAST CUSTOM_TXT_CDS <CON_TC_SNM8>
J 0
(-7700 4975);
FORCEPROP 1 LAST CUSTOM_TXT_CDS <CON_TC_SNM10>
J 0
(-7700 4775);
FORCEPROP 1 LAST CUSTOM_TXT_CDS <CON_TC_SNM12>
J 0
(-7700 4575);
FORCEPROP 1 LAST CUSTOM_TXT_CDS <CON_TC_SNM14>
J 0
(-7700 4375);
FORCEPROP 1 LAST CUSTOM_TXT_CDS <CON_TC_SNM15>
J 0
(-7700 4275);
FORCEPROP 1 LAST CUSTOM_TXT_CDS <CON_TC_SNM17>
J 0
(-7700 4075);
FORCEPROP 1 LAST CUSTOM_TXT_CDS <CON_TC_SNM18>
J 0
(-7700 3975);
FORCEPROP 1 LAST CUSTOM_TXT_CDS <CON_TC_SNM19>
J 0
(-7700 3875);
FORCEPROP 1 LAST CUSTOM_TXT_CDS <CON_TC_SNM20>
J 0
(-7700 3775);
FORCEPROP 1 LAST CUSTOM_TXT_CDS <CON_TC_SNM21>
J 0
(-7700 3675);
FORCEPROP 1 LAST CUSTOM_TXT_CDS <CON_TC_SNM22>
J 0
(-7700 3575);
FORCEPROP 1 LAST CUSTOM_TXT_CDS <CON_TC_SNM23>
J 0
(-7700 3475);
FORCEPROP 1 LAST CUSTOM_TXT_CDS <CON_TC_SNM24>
J 0
(-7700 3375);
FORCEPROP 1 LAST CUSTOM_TXT_CDS <CON_TC_SNM25>
J 0
(-7700 3275);
FORCEPROP 1 LAST CUSTOM_TXT_CDS <CON_TC_SNM26>
J 0
(-7700 3175);
FORCEPROP 1 LAST CUSTOM_TXT_CDS <CON_TC_SNM27>
J 0
(-7700 3075);
FORCEPROP 1 LAST CUSTOM_TXT_CDS <CON_TC_SNM28>
J 0
(-7700 2975);
FORCEPROP 1 LAST CUSTOM_TXT_CDS <CON_TC_SNM29>
J 0
(-7700 2875);
FORCEPROP 1 LAST CUSTOM_TXT_CDS <CON_TC_SNM30>
J 0
(-7700 2775);
FORCEPROP 1 LAST CUSTOM_TXT_CDS <CON_TC_SNM31>
J 0
(-7700 2675);
FORCEPROP 1 LAST CUSTOM_TXT_CDS <CON_TC_SNM32>
J 0
(-7700 2575);
FORCEPROP 1 LAST CUSTOM_TXT_CDS <CON_TC_SNM33>
J 0
(-7700 2475);
FORCEPROP 1 LAST CUSTOM_TXT_CDS <CON_TC_SNM34>
J 0
(-7700 2375);
FORCEPROP 1 LAST CUSTOM_TXT_CDS <CON_TC_SNM35>
J 0
(-7700 2275);
FORCEPROP 1 LAST CUSTOM_TXT_CDS <CON_TC_SNM36>
J 0
(-7700 2175);
FORCEPROP 1 LAST CUSTOM_TXT_CDS <CON_TC_SNM37>
J 0
(-7700 2075);
FORCEPROP 1 LAST CUSTOM_TXT_CDS <CON_TC_SNM38>
J 0
(-7700 1975);
FORCEPROP 1 LAST CUSTOM_TXT_CDS <CON_TC_SNM39>
J 0
(-7700 1875);
FORCEPROP 1 LAST CUSTOM_TXT_CDS <CON_TC_SNM40>
J 0
(-7700 1775);
FORCEPROP 1 LAST CUSTOM_TXT_CDS <CON_TC_SNM41>
J 0
(-5200 5675);
FORCEPROP 1 LAST CUSTOM_TXT_CDS <CON_TC_SNM42>
J 0
(-5200 5575);
FORCEPROP 1 LAST CUSTOM_TXT_CDS <CON_TC_SNM43>
J 0
(-5200 5475);
FORCEPROP 1 LAST CUSTOM_TXT_CDS <CON_TC_SNM44>
J 0
(-5200 5375);
FORCEPROP 1 LAST CUSTOM_TXT_CDS <CON_TC_SNM45>
J 0
(-5200 5275);
FORCEPROP 1 LAST CUSTOM_TXT_CDS <CON_TC_SNM46>
J 0
(-5200 5175);
FORCEPROP 1 LAST CUSTOM_TXT_CDS <CON_TC_SNM47>
J 0
(-5200 5075);
FORCEPROP 1 LAST CUSTOM_TXT_CDS <CON_TC_SNM48>
J 0
(-5200 4975);
FORCEPROP 1 LAST CUSTOM_TXT_CDS <CON_TC_SNM49>
J 0
(-5200 4875);
FORCEPROP 1 LAST CUSTOM_TXT_CDS <CON_TC_SNM50>
J 0
(-5200 4775);
FORCEPROP 1 LAST CUSTOM_TXT_CDS <CON_TC_SNM51>
J 0
(-5200 4675);
FORCEPROP 1 LAST CUSTOM_TXT_CDS <CON_TC_SNM52>
J 0
(-5200 4575);
FORCEPROP 1 LAST CUSTOM_TXT_CDS <CON_TC_SNM53>
J 0
(-5200 4475);
FORCEPROP 1 LAST CUSTOM_TXT_CDS <CON_TC_SNM54>
J 0
(-5200 4375);
FORCEPROP 1 LAST CUSTOM_TXT_CDS <CON_TC_SNM55>
J 0
(-5200 4275);
FORCEPROP 1 LAST CUSTOM_TXT_CDS <CON_TC_SNM56>
J 0
(-5200 4175);
FORCEPROP 1 LAST CUSTOM_TXT_CDS <CON_TC_SNM57>
J 0
(-5200 4075);
FORCEPROP 1 LAST CUSTOM_TXT_CDS <CON_TC_SNM58>
J 0
(-5200 3975);
FORCEPROP 1 LAST CUSTOM_TXT_CDS <CON_TC_SNM59>
J 0
(-5200 3875);
FORCEPROP 1 LAST CUSTOM_TXT_CDS <CON_TC_SNM60>
J 0
(-5200 3775);
FORCEPROP 1 LAST CUSTOM_TXT_CDS <CON_TC_SNM61>
J 0
(-5200 3675);
FORCEPROP 1 LAST CUSTOM_TXT_CDS <CON_TC_SNM62>
J 0
(-5200 3575);
FORCEPROP 1 LAST CUSTOM_TXT_CDS <CON_TC_SNM63>
J 0
(-5200 3475);
FORCEPROP 1 LAST CUSTOM_TXT_CDS <CON_TC_SNM64>
J 0
(-5200 3375);
FORCEPROP 1 LAST CUSTOM_TXT_CDS <CON_TC_SNM65>
J 0
(-5200 3275);
FORCEPROP 1 LAST CUSTOM_TXT_CDS <CON_TC_SNM66>
J 0
(-5200 3175);
FORCEPROP 1 LAST CUSTOM_TXT_CDS <CON_TC_SNM67>
J 0
(-5200 3075);
FORCEPROP 1 LAST CUSTOM_TXT_CDS <CON_TC_SNM68>
J 0
(-5200 2975);
FORCEPROP 1 LAST CUSTOM_TXT_CDS <CON_TC_SNM69>
J 0
(-5200 2875);
FORCEPROP 1 LAST CUSTOM_TXT_CDS <CON_TC_SNM70>
J 0
(-5200 2775);
FORCEPROP 1 LAST CUSTOM_TXT_CDS <CON_TC_SNM71>
J 0
(-5200 2675);
FORCEPROP 1 LAST CUSTOM_TXT_CDS <CON_TC_SNM72>
J 0
(-5200 2575);
FORCEPROP 1 LAST CUSTOM_TXT_CDS <CON_TC_SNM73>
J 0
(-5200 2475);
FORCEPROP 1 LAST CUSTOM_TXT_CDS <CON_TC_SNM74>
J 0
(-5200 2375);
FORCEPROP 1 LAST CUSTOM_TXT_CDS <CON_TC_SNM75>
J 0
(-5200 2275);
FORCEPROP 1 LAST CUSTOM_TXT_CDS <CON_TC_SNM76>
J 0
(-5200 2175);
FORCEPROP 1 LAST CUSTOM_TXT_CDS <CON_TC_SNM77>
J 0
(-5200 2075);
FORCEPROP 1 LAST CUSTOM_TXT_CDS <CON_TC_SNM78>
J 0
(-5200 1975);
FORCEPROP 1 LAST CUSTOM_TXT_CDS <CON_TC_SNM79>
J 0
(-5200 1875);
FORCEPROP 1 LAST CUSTOM_TXT_CDS <CON_TC_SNM80>
J 0
(-5200 1775);
FORCEPROP 1 LAST CUSTOM_TXT_CDS <CON_TC_SNM81>
J 0
(-2700 5675);
FORCEPROP 1 LAST CUSTOM_TXT_CDS <CON_TC_SNM82>
J 0
(-2700 5575);
FORCEPROP 1 LAST CUSTOM_TXT_CDS <CON_TC_SNM83>
J 0
(-2700 5475);
FORCEPROP 1 LAST CUSTOM_TXT_CDS <CON_TC_SNM84>
J 0
(-2700 5375);
FORCEPROP 1 LAST CUSTOM_TXT_CDS <CON_TC_SNM85>
J 0
(-2700 5275);
FORCEPROP 1 LAST CUSTOM_TXT_CDS <CON_TC_SNM86>
J 0
(-2700 5175);
FORCEPROP 1 LAST CUSTOM_TXT_CDS <CON_TC_SNM87>
J 0
(-2700 5075);
FORCEPROP 1 LAST CUSTOM_TXT_CDS <CON_TC_SNM88>
J 0
(-2700 4975);
FORCEPROP 1 LAST CUSTOM_TXT_CDS <CON_TC_SNM89>
J 0
(-2700 4875);
FORCEPROP 1 LAST CUSTOM_TXT_CDS <CON_TC_SNM90>
J 0
(-2700 4775);
FORCEPROP 1 LAST CUSTOM_TXT_CDS <CON_TC_SNM91>
J 0
(-2700 4675);
FORCEPROP 1 LAST CUSTOM_TXT_CDS <CON_TC_SNM92>
J 0
(-2700 4575);
FORCEPROP 1 LAST CUSTOM_TXT_CDS <CON_TC_SNM93>
J 0
(-2700 4475);
FORCEPROP 1 LAST CUSTOM_TXT_CDS <CON_TC_SNM94>
J 0
(-2700 4375);
FORCEPROP 1 LAST CUSTOM_TXT_CDS <CON_TC_SNM95>
J 0
(-2700 4275);
FORCEPROP 1 LAST CUSTOM_TXT_CDS <CON_TC_SNM96>
J 0
(-2700 4175);
FORCEPROP 1 LAST CUSTOM_TXT_CDS <CON_TC_SNM97>
J 0
(-2700 4075);
FORCEPROP 1 LAST CUSTOM_TXT_CDS <CON_TC_SNM98>
J 0
(-2700 3975);
FORCEPROP 1 LAST CUSTOM_TXT_CDS <CON_TC_SNM99>
J 0
(-2700 3875);
FORCEPROP 1 LAST CUSTOM_TXT_CDS <CON_TC_SNM100>
J 0
(-2700 3775);
FORCEPROP 1 LAST CUSTOM_TXT_CDS <CON_TC_SNM101>
J 0
(-2700 3675);
FORCEPROP 1 LAST CUSTOM_TXT_CDS <CON_TC_SNM102>
J 0
(-2700 3575);
FORCEPROP 1 LAST CUSTOM_TXT_CDS <CON_TC_SNM103>
J 0
(-2700 3475);
FORCEPROP 1 LAST CUSTOM_TXT_CDS <CON_TC_SNM104>
J 0
(-2700 3375);
FORCEPROP 1 LAST CUSTOM_TXT_CDS <CON_TC_SNM105>
J 0
(-2700 3275);
FORCEPROP 1 LAST CUSTOM_TXT_CDS <CON_TC_SNM106>
J 0
(-2700 3175);
FORCEPROP 1 LAST CUSTOM_TXT_CDS <CON_TC_SNM107>
J 0
(-2700 3075);
FORCEPROP 1 LAST CUSTOM_TXT_CDS <CON_TC_SNM108>
J 0
(-2700 2975);
FORCEPROP 1 LAST CUSTOM_TXT_CDS <CON_TC_SNM109>
J 0
(-2700 2875);
FORCEPROP 1 LAST CUSTOM_TXT_CDS <CON_TC_SNM110>
J 0
(-2700 2775);
FORCEPROP 1 LAST CUSTOM_TXT_CDS <CON_TC_SNM111>
J 0
(-2700 2675);
FORCEPROP 1 LAST CUSTOM_TXT_CDS <CON_TC_SNM112>
J 0
(-2700 2575);
FORCEPROP 1 LAST CUSTOM_TXT_CDS <CON_TC_SNM113>
J 0
(-2700 2475);
FORCEPROP 1 LAST CUSTOM_TXT_CDS <CON_TC_SNM114>
J 0
(-2700 2375);
FORCEPROP 1 LAST CUSTOM_TXT_CDS <CON_TC_SNM115>
J 0
(-2700 2275);
FORCEPROP 1 LAST CUSTOM_TXT_CDS <CON_TC_SNM116>
J 0
(-2700 2175);
FORCEPROP 1 LAST CUSTOM_TXT_CDS <CON_TC_SNM117>
J 0
(-2700 2075);
FORCEPROP 1 LAST CUSTOM_TXT_CDS <CON_TC_SNM118>
J 0
(-2700 1975);
FORCEPROP 1 LAST CUSTOM_TXT_CDS <CON_TC_SNM119>
J 0
(-2700 1875);
FORCEPROP 1 LAST CUSTOM_TXT_CDS <CON_TC_SNM120>
J 0
(-2700 1775);
FORCEPROP 1 LAST CUSTOM_TXT_CDS <CON_TC_SNO1>
J 2
(-7800 5675);
FORCEPROP 1 LAST CUSTOM_TXT_CDS <CON_TC_SNO2>
J 2
(-7800 5575);
FORCEPROP 1 LAST CUSTOM_TXT_CDS <CON_TC_SNO3>
J 2
(-7800 5475);
FORCEPROP 1 LAST CUSTOM_TXT_CDS <CON_TC_SNO4>
J 2
(-7800 5375);
FORCEPROP 1 LAST CUSTOM_TXT_CDS <CON_TC_SNO5>
J 2
(-7800 5275);
FORCEPROP 1 LAST CUSTOM_TXT_CDS <CON_TC_SNO7>
J 2
(-7800 5075);
FORCEPROP 1 LAST CUSTOM_TXT_CDS <CON_TC_SNO8>
J 2
(-7800 4975);
FORCEPROP 1 LAST CUSTOM_TXT_CDS <CON_TC_SNO9>
J 2
(-7800 4875);
FORCEPROP 1 LAST CUSTOM_TXT_CDS <CON_TC_SNO10>
J 2
(-7800 4775);
FORCEPROP 1 LAST CUSTOM_TXT_CDS <CON_TC_SNO11>
J 2
(-7800 4675);
FORCEPROP 1 LAST CUSTOM_TXT_CDS <CON_TC_SNO12>
J 2
(-7800 4575);
FORCEPROP 1 LAST CUSTOM_TXT_CDS <CON_TC_SNO13>
J 2
(-7800 4475);
FORCEPROP 1 LAST CUSTOM_TXT_CDS <CON_TC_SNO14>
J 2
(-7800 4375);
FORCEPROP 1 LAST CUSTOM_TXT_CDS <CON_TC_SNO15>
J 2
(-7800 4275);
FORCEPROP 1 LAST CUSTOM_TXT_CDS <CON_TC_SNO16>
J 2
(-7800 4175);
FORCEPROP 1 LAST CUSTOM_TXT_CDS <CON_TC_SNO17>
J 2
(-7800 4075);
FORCEPROP 1 LAST CUSTOM_TXT_CDS <CON_TC_SNO18>
J 2
(-7800 3975);
FORCEPROP 1 LAST CUSTOM_TXT_CDS <CON_TC_SNO19>
J 2
(-7800 3875);
FORCEPROP 1 LAST CUSTOM_TXT_CDS <CON_TC_SNO20>
J 2
(-7800 3775);
FORCEPROP 1 LAST CUSTOM_TXT_CDS <CON_TC_SNO21>
J 2
(-7800 3675);
FORCEPROP 1 LAST CUSTOM_TXT_CDS <CON_TC_SNO22>
J 2
(-7800 3575);
FORCEPROP 1 LAST CUSTOM_TXT_CDS <CON_TC_SNO23>
J 2
(-7800 3475);
FORCEPROP 1 LAST CUSTOM_TXT_CDS <CON_TC_SNO24>
J 2
(-7800 3375);
FORCEPROP 1 LAST CUSTOM_TXT_CDS <CON_TC_SNO25>
J 2
(-7800 3275);
FORCEPROP 1 LAST CUSTOM_TXT_CDS <CON_TC_SNO26>
J 2
(-7800 3175);
FORCEPROP 1 LAST CUSTOM_TXT_CDS <CON_TC_SNO27>
J 2
(-7800 3075);
FORCEPROP 1 LAST CUSTOM_TXT_CDS <CON_TC_SNO28>
J 2
(-7800 2975);
FORCEPROP 1 LAST CUSTOM_TXT_CDS <CON_TC_SNO29>
J 2
(-7800 2875);
FORCEPROP 1 LAST CUSTOM_TXT_CDS <CON_TC_SNO30>
J 2
(-7800 2775);
FORCEPROP 1 LAST CUSTOM_TXT_CDS <CON_TC_SNO31>
J 2
(-7800 2675);
FORCEPROP 1 LAST CUSTOM_TXT_CDS <CON_TC_SNO32>
J 2
(-7800 2575);
FORCEPROP 1 LAST CUSTOM_TXT_CDS <CON_TC_SNO33>
J 2
(-7800 2475);
FORCEPROP 1 LAST CUSTOM_TXT_CDS <CON_TC_SNO34>
J 2
(-7800 2375);
FORCEPROP 1 LAST CUSTOM_TXT_CDS <CON_TC_SNO35>
J 2
(-7800 2275);
FORCEPROP 1 LAST CUSTOM_TXT_CDS <CON_TC_SNO36>
J 2
(-7800 2175);
FORCEPROP 1 LAST CUSTOM_TXT_CDS <CON_TC_SNO37>
J 2
(-7800 2075);
FORCEPROP 1 LAST CUSTOM_TXT_CDS <CON_TC_SNO38>
J 2
(-7800 1975);
FORCEPROP 1 LAST CUSTOM_TXT_CDS <CON_TC_SNO39>
J 2
(-7800 1875);
FORCEPROP 1 LAST CUSTOM_TXT_CDS <CON_TC_SNO40>
J 2
(-7800 1775);
FORCEPROP 1 LAST CUSTOM_TXT_CDS <CON_TC_SNO41>
J 2
(-5300 5675);
FORCEPROP 1 LAST CUSTOM_TXT_CDS <CON_TC_SNO42>
J 2
(-5300 5575);
FORCEPROP 1 LAST CUSTOM_TXT_CDS <CON_TC_SNO43>
J 2
(-5300 5475);
FORCEPROP 1 LAST CUSTOM_TXT_CDS <CON_TC_SNO44>
J 2
(-5300 5375);
FORCEPROP 1 LAST CUSTOM_TXT_CDS <CON_TC_SNO45>
J 2
(-5300 5275);
FORCEPROP 1 LAST CUSTOM_TXT_CDS <CON_TC_SNO46>
J 2
(-5300 5175);
FORCEPROP 1 LAST CUSTOM_TXT_CDS <CON_TC_SNO47>
J 2
(-5300 5075);
FORCEPROP 1 LAST CUSTOM_TXT_CDS <CON_TC_SNO48>
J 2
(-5300 4975);
FORCEPROP 1 LAST CUSTOM_TXT_CDS <CON_TC_SNO49>
J 2
(-5300 4875);
FORCEPROP 1 LAST CUSTOM_TXT_CDS <CON_TC_SNO50>
J 2
(-5300 4775);
FORCEPROP 1 LAST CUSTOM_TXT_CDS <CON_TC_SNO51>
J 2
(-5300 4675);
FORCEPROP 1 LAST CUSTOM_TXT_CDS <CON_TC_SNO52>
J 2
(-5300 4575);
FORCEPROP 1 LAST CUSTOM_TXT_CDS <CON_TC_SNO53>
J 2
(-5300 4475);
FORCEPROP 1 LAST CUSTOM_TXT_CDS <CON_TC_SNO54>
J 2
(-5300 4375);
FORCEPROP 1 LAST CUSTOM_TXT_CDS <CON_TC_SNO55>
J 2
(-5300 4275);
FORCEPROP 1 LAST CUSTOM_TXT_CDS <CON_TC_SNO56>
J 2
(-5300 4175);
FORCEPROP 1 LAST CUSTOM_TXT_CDS <CON_TC_SNO57>
J 2
(-5300 4075);
FORCEPROP 1 LAST CUSTOM_TXT_CDS <CON_TC_SNO58>
J 2
(-5300 3975);
FORCEPROP 1 LAST CUSTOM_TXT_CDS <CON_TC_SNO59>
J 2
(-5300 3875);
FORCEPROP 1 LAST CUSTOM_TXT_CDS <CON_TC_SNO60>
J 2
(-5300 3775);
FORCEPROP 1 LAST CUSTOM_TXT_CDS <CON_TC_SNO61>
J 2
(-5300 3675);
FORCEPROP 1 LAST CUSTOM_TXT_CDS <CON_TC_SNO62>
J 2
(-5300 3575);
FORCEPROP 1 LAST CUSTOM_TXT_CDS <CON_TC_SNO63>
J 2
(-5300 3475);
FORCEPROP 1 LAST CUSTOM_TXT_CDS <CON_TC_SNO64>
J 2
(-5300 3375);
FORCEPROP 1 LAST CUSTOM_TXT_CDS <CON_TC_SNO65>
J 2
(-5300 3275);
FORCEPROP 1 LAST CUSTOM_TXT_CDS <CON_TC_SNO66>
J 2
(-5300 3175);
FORCEPROP 1 LAST CUSTOM_TXT_CDS <CON_TC_SNO67>
J 2
(-5300 3075);
FORCEPROP 1 LAST CUSTOM_TXT_CDS <CON_TC_SNO68>
J 2
(-5300 2975);
FORCEPROP 1 LAST CUSTOM_TXT_CDS <CON_TC_SNO69>
J 2
(-5300 2875);
FORCEPROP 1 LAST CUSTOM_TXT_CDS <CON_TC_SNO70>
J 2
(-5300 2775);
FORCEPROP 1 LAST CUSTOM_TXT_CDS <CON_TC_SNO71>
J 2
(-5300 2675);
FORCEPROP 1 LAST CUSTOM_TXT_CDS <CON_TC_SNO72>
J 2
(-5300 2575);
FORCEPROP 1 LAST CUSTOM_TXT_CDS <CON_TC_SNO73>
J 2
(-5300 2475);
FORCEPROP 1 LAST CUSTOM_TXT_CDS <CON_TC_SNO74>
J 2
(-5300 2375);
FORCEPROP 1 LAST CUSTOM_TXT_CDS <CON_TC_SNO75>
J 2
(-5300 2275);
FORCEPROP 1 LAST CUSTOM_TXT_CDS <CON_TC_SNO76>
J 2
(-5300 2175);
FORCEPROP 1 LAST CUSTOM_TXT_CDS <CON_TC_SNO77>
J 2
(-5300 2075);
FORCEPROP 1 LAST CUSTOM_TXT_CDS <CON_TC_SNO78>
J 2
(-5300 1975);
FORCEPROP 1 LAST CUSTOM_TXT_CDS <CON_TC_SNO79>
J 2
(-5300 1875);
FORCEPROP 1 LAST CUSTOM_TXT_CDS <CON_TC_SNO80>
J 2
(-5300 1775);
FORCEPROP 1 LAST CUSTOM_TXT_CDS <CON_TC_SNO81>
J 2
(-2800 5675);
FORCEPROP 1 LAST CUSTOM_TXT_CDS <CON_TC_SNO82>
J 2
(-2800 5575);
FORCEPROP 1 LAST CUSTOM_TXT_CDS <CON_TC_SNO83>
J 2
(-2800 5475);
FORCEPROP 1 LAST CUSTOM_TXT_CDS <CON_TC_SNO84>
J 2
(-2800 5375);
FORCEPROP 1 LAST CUSTOM_TXT_CDS <CON_TC_SNO85>
J 2
(-2800 5275);
FORCEPROP 1 LAST CUSTOM_TXT_CDS <CON_TC_SNO86>
J 2
(-2800 5175);
FORCEPROP 1 LAST CUSTOM_TXT_CDS <CON_TC_SNO87>
J 2
(-2800 5075);
FORCEPROP 1 LAST CUSTOM_TXT_CDS <CON_TC_SNO88>
J 2
(-2800 4975);
FORCEPROP 1 LAST CUSTOM_TXT_CDS <CON_TC_SNO89>
J 2
(-2800 4875);
FORCEPROP 1 LAST CUSTOM_TXT_CDS <CON_TC_SNO90>
J 2
(-2800 4775);
FORCEPROP 1 LAST CUSTOM_TXT_CDS <CON_TC_SNO91>
J 2
(-2800 4675);
FORCEPROP 1 LAST CUSTOM_TXT_CDS <CON_TC_SNO92>
J 2
(-2800 4575);
FORCEPROP 1 LAST CUSTOM_TXT_CDS <CON_TC_SNO93>
J 2
(-2800 4475);
FORCEPROP 1 LAST CUSTOM_TXT_CDS <CON_TC_SNO94>
J 2
(-2800 4375);
FORCEPROP 1 LAST CUSTOM_TXT_CDS <CON_TC_SNO95>
J 2
(-2800 4275);
FORCEPROP 1 LAST CUSTOM_TXT_CDS <CON_TC_SNO96>
J 2
(-2800 4175);
FORCEPROP 1 LAST CUSTOM_TXT_CDS <CON_TC_SNO97>
J 2
(-2800 4075);
FORCEPROP 1 LAST CUSTOM_TXT_CDS <CON_TC_SNO98>
J 2
(-2800 3975);
FORCEPROP 1 LAST CUSTOM_TXT_CDS <CON_TC_SNO99>
J 2
(-2800 3875);
FORCEPROP 1 LAST CUSTOM_TXT_CDS <CON_TC_SNO100>
J 2
(-2800 3775);
FORCEPROP 1 LAST CUSTOM_TXT_CDS <CON_TC_SNO101>
J 2
(-2800 3675);
FORCEPROP 1 LAST CUSTOM_TXT_CDS <CON_TC_SNO102>
J 2
(-2800 3575);
FORCEPROP 1 LAST CUSTOM_TXT_CDS <CON_TC_SNO103>
J 2
(-2800 3475);
FORCEPROP 1 LAST CUSTOM_TXT_CDS <CON_TC_SNO104>
J 2
(-2800 3375);
FORCEPROP 1 LAST CUSTOM_TXT_CDS <CON_TC_SNO105>
J 2
(-2800 3275);
FORCEPROP 1 LAST CUSTOM_TXT_CDS <CON_TC_SNO106>
J 2
(-2800 3175);
FORCEPROP 1 LAST CUSTOM_TXT_CDS <CON_TC_SNO107>
J 2
(-2800 3075);
FORCEPROP 1 LAST CUSTOM_TXT_CDS <CON_TC_SNO108>
J 2
(-2800 2975);
FORCEPROP 1 LAST CUSTOM_TXT_CDS <CON_TC_SNO109>
J 2
(-2800 2875);
FORCEPROP 1 LAST CUSTOM_TXT_CDS <CON_TC_SNO110>
J 2
(-2800 2775);
FORCEPROP 1 LAST CUSTOM_TXT_CDS <CON_TC_SNO111>
J 2
(-2800 2675);
FORCEPROP 1 LAST CUSTOM_TXT_CDS <CON_TC_SNO112>
J 2
(-2800 2575);
FORCEPROP 1 LAST CUSTOM_TXT_CDS <CON_TC_SNO113>
J 2
(-2800 2475);
FORCEPROP 1 LAST CUSTOM_TXT_CDS <CON_TC_SNO114>
J 2
(-2800 2375);
FORCEPROP 1 LAST CUSTOM_TXT_CDS <CON_TC_SNO115>
J 2
(-2800 2275);
FORCEPROP 1 LAST CUSTOM_TXT_CDS <CON_TC_SNO116>
J 2
(-2800 2175);
FORCEPROP 1 LAST CUSTOM_TXT_CDS <CON_TC_SNO117>
J 2
(-2800 2075);
FORCEPROP 1 LAST CUSTOM_TXT_CDS <CON_TC_SNO118>
J 2
(-2800 1975);
FORCEPROP 1 LAST CUSTOM_TXT_CDS <CON_TC_SNO119>
J 2
(-2800 1875);
FORCEPROP 1 LAST CUSTOM_TXT_CDS <CON_TC_SNO120>
J 2
(-2800 1775);
FORCEPROP 1 LAST CUSTOM_TXT_CDS <Q_NUMBER>
J 0
(-1500 200);
DISPLAY 1.212766 (-1500 200);
FORCEPROP 1 LAST CUSTOM_TXT_CDS <Q_PROJ>
J 0
(-2475 200);
DISPLAY 1.212766 (-2475 200);
FORCEPROP 1 LAST CUSTOM_TXT_CDS <Q_REV>
J 0
(-275 200);
DISPLAY 1.212766 (-275 200);
FORCEPROP 1 LAST CUSTOM_TXT_CDS <CON_LAST_MODIFIED>
J 0
(-2000 125);
DISPLAY 0.978723 (-2000 125);
FORCEPROP 1 LAST CUSTOM_TXT_CDS <CON_PAGE_NUM> OF <CON_TOTAL_PAGES>
J 0
(-538 113);
DISPLAY 0.978723 (-538 113);
FORCEPROP 1 LAST CUSTOM_TXT_CDS <CON_TC_SNO6>
J 2
(-7800 5175);
FORCEPROP 1 LAST CUSTOM_TXT_CDS <CON_TC_SNM9>
J 0
(-7700 4875);
FORCEPROP 1 LAST CUSTOM_TXT_CDS <CON_TC_SNM11>
J 0
(-7700 4675);
FORCEPROP 1 LAST CUSTOM_TXT_CDS <CON_TC_SNM13>
J 0
(-7700 4475);
FORCEPROP 1 LAST CUSTOM_TXT_CDS <CON_TC_SNM16>
J 0
(-7700 4175);
FORCEPROP 2 LAST CUSTOM_TXT_CDS <NAME_2>
J 0
(-3300 150);
DISPLAY 1.021277 (-3300 150);
FORCEPROP 2 LAST CUSTOM_TXT_CDS <NAME_1>
J 0
(-3300 275);
DISPLAY 1.021277 (-3300 275);
FORCEPROP 1 LAST TOC_SYMBOL TRUE
J 0
(-9274 6552);
DISPLAY 0.978723 (-9274 6552);
PAINT GREEN (-9274 6552);
DISPLAY INVISIBLE (-9274 6552);
FORCEPROP 2 LAST PAGE_BORDER TRUE
J 0
(-7990 5350);
DISPLAY 0.638298 (-7990 5350);
PAINT PINK (-7990 5350);
DISPLAY INVISIBLE (-7990 5350);
FORCEPROP 2 LAST CDS_LIB pure_quanta
J 0
(-100 100);
DISPLAY INVISIBLE (-100 100);
FORCEPROP 2 LAST CDS_XR_PAGE_TITLE CR-4 : @T6G_MB_LIB.T6G(SCH_1):PAGE4
J 0
(-7990 5350);
DISPLAY 0.638298 (-7990 5350);
PAINT PINK (-7990 5350);
DISPLAY INVISIBLE (-7990 5350);
FORCEPROP 2 LAST CUSTOM_TXT_CDS <XR_PAGE_TITLE>
J 0
(-7990 5350);
DISPLAY 0.638298 (-7990 5350);
PAINT PINK (-7990 5350);
DISPLAY INVISIBLE (-7990 5350);
FORCEPROP 1 LAST COMMENT_BODY TRUE
J 0
(-1249 126);
DISPLAY 0.978723 (-1249 126);
PAINT GREEN (-1249 126);
DISPLAY INVISIBLE (-1249 126);
FORCEPROP 1 LAST Q_DEPT BU9
J 1
(-3851 149);
DISPLAY 1.957447 (-3851 149);
PAINT GREEN (-3851 149);
DISPLAY INVISIBLE (-3851 149);
FORCEPROP 0 LAST CDS_CON_LAST_MODIFIED Thu Aug 24 10:13:29 2023
J 0
(-2000 125);
DISPLAY INVISIBLE (-2000 125);
QUIT
